(kicad_pcb
	(version 20260206)
	(generator "pcbnew")
	(generator_version "10.0")
	(general
		(thickness 1.6)
		(legacy_teardrops no)
	)
	(paper "A4")
	(title_block
		(title "04192023_DAF0TMB3IC0_F0TG_MB_C_brd_V02_OCP.brd")
		(comment 1 "Grand Teton / footprint 2449 of 8354 (J23), pads 1-113 of 291")
	)
	(layers
		(0 "F.Cu" signal "TOP")
		(4 "In1.Cu" signal "GND")
		(6 "In2.Cu" signal "IN1")
		(8 "In3.Cu" signal "GND1")
		(10 "In4.Cu" signal "IN2")
		(12 "In5.Cu" signal "GND2")
		(14 "In6.Cu" signal "IN3")
		(16 "In7.Cu" signal "GND3")
		(18 "In8.Cu" signal "VCC")
		(20 "In9.Cu" signal "VCC1")
		(22 "In10.Cu" signal "GND4")
		(24 "In11.Cu" signal "IN4")
		(26 "In12.Cu" signal "GND5")
		(28 "In13.Cu" signal "IN5")
		(30 "In14.Cu" signal "GND6")
		(32 "In15.Cu" signal "IN6")
		(34 "In16.Cu" signal "GND7")
		(2 "B.Cu" signal "BOTTOM")
		(9 "F.Adhes" user "F.Adhesive")
		(11 "B.Adhes" user "B.Adhesive")
		(13 "F.Paste" user "Package Geometry/Pastemask Top")
		(15 "B.Paste" user "Package Geometry/Pastemask Bottom")
		(5 "F.SilkS" user "Ref Des/Silkscreen Top")
		(7 "B.SilkS" user "Ref Des/Silkscreen Bottom")
		(1 "F.Mask" user "Board Geometry/Soldermask Top")
		(3 "B.Mask" user "Board Geometry/Soldermask Bottom")
		(17 "Dwgs.User" user "User.Drawings")
		(19 "Cmts.User" user "User.Comments")
		(21 "Eco1.User" user "User.Eco1")
		(23 "Eco2.User" user "User.Eco2")
		(25 "Edge.Cuts" user "Board Geometry/Outline")
		(27 "Margin" user)
		(31 "F.CrtYd" user "Package Geometry/Place Bound Top")
		(29 "B.CrtYd" user "Package Geometry/Place Bound Bottom")
		(35 "F.Fab" user "Ref Des/Assembly Top")
		(33 "B.Fab" user "Ref Des/Assembly Bottom")
	)
	(footprint ""
		(layer "F.Cu")
		(at 267.598144 -255.560068 180)
		(property "Reference" "J23"
			(at -2.2098 -81.984088 0)
			(unlocked yes)
			(layer "F.SilkS")
			(effects
				(font
					(size 0.7874 0.5842)
					(thickness 0.1524)
				)
			)
		)
		(property "Value" ""
			(at 0 0 180)
			(layer "F.Fab")
			(effects
				(font
					(size 1.27 1.27)
				)
			)
		)
		(duplicate_pad_numbers_are_jumpers no)
		(pad "1" smd rect
			(at -2.050034 -63.324994 90)
			(size 0.519938 1.4986)
			(layers "F.Cu" "F.Mask" "F.Paste")
			(net "P12V_MEM_CPU0")
		)
		(pad "2" smd rect
			(at -2.050034 -62.47511 90)
			(size 0.519938 1.4986)
			(layers "F.Cu" "F.Mask" "F.Paste")
			(net "Net_2319")
		)
		(pad "3" smd rect
			(at -2.050034 -61.624972 90)
			(size 0.519938 1.4986)
			(layers "F.Cu" "F.Mask" "F.Paste")
			(net "P3V3_AUX")
		)
		(pad "4" smd rect
			(at -2.050034 -60.775088 90)
			(size 0.519938 1.4986)
			(layers "F.Cu" "F.Mask" "F.Paste")
			(net "I3C_SPD_DDRF_CPU0_SCL")
		)
		(pad "5" smd rect
			(at -2.050034 -59.92495 90)
			(size 0.519938 1.4986)
			(layers "F.Cu" "F.Mask" "F.Paste")
			(net "I3C_SPD_DDRF_CPU0_SDA")
		)
		(pad "6" smd rect
			(at -2.050034 -59.075066 90)
			(size 0.519938 1.4986)
			(layers "F.Cu" "F.Mask" "F.Paste")
			(net "GND")
		)
		(pad "7" smd rect
			(at -2.050034 -58.224928 90)
			(size 0.519938 1.4986)
			(layers "F.Cu" "F.Mask" "F.Paste")
			(net "M_F_CPU0_SA_DQ<0>")
		)
		(pad "8" smd rect
			(at -2.050034 -57.375044 90)
			(size 0.519938 1.4986)
			(layers "F.Cu" "F.Mask" "F.Paste")
			(net "GND")
		)
		(pad "9" smd rect
			(at -2.050034 -56.524906 90)
			(size 0.519938 1.4986)
			(layers "F.Cu" "F.Mask" "F.Paste")
			(net "M_F_CPU0_SA_DQ<1>")
		)
		(pad "10" smd rect
			(at -2.050034 -55.675022 90)
			(size 0.519938 1.4986)
			(layers "F.Cu" "F.Mask" "F.Paste")
			(net "GND")
		)
		(pad "11" smd rect
			(at -2.050034 -54.824884 90)
			(size 0.519938 1.4986)
			(layers "F.Cu" "F.Mask" "F.Paste")
			(net "M_F_CPU0_SA_DQS_DP<0>")
		)
		(pad "12" smd rect
			(at -2.050034 -53.975 90)
			(size 0.519938 1.4986)
			(layers "F.Cu" "F.Mask" "F.Paste")
			(net "M_F_CPU0_SA_DQS_DN<0>")
		)
		(pad "13" smd rect
			(at -2.050034 -53.125116 90)
			(size 0.519938 1.4986)
			(layers "F.Cu" "F.Mask" "F.Paste")
			(net "GND")
		)
		(pad "14" smd rect
			(at -2.050034 -52.274978 90)
			(size 0.519938 1.4986)
			(layers "F.Cu" "F.Mask" "F.Paste")
			(net "M_F_CPU0_SA_DQ<4>")
		)
		(pad "15" smd rect
			(at -2.050034 -51.425094 90)
			(size 0.519938 1.4986)
			(layers "F.Cu" "F.Mask" "F.Paste")
			(net "GND")
		)
		(pad "16" smd rect
			(at -2.050034 -50.574956 90)
			(size 0.519938 1.4986)
			(layers "F.Cu" "F.Mask" "F.Paste")
			(net "M_F_CPU0_SA_DQ<5>")
		)
		(pad "17" smd rect
			(at -2.050034 -49.725072 90)
			(size 0.519938 1.4986)
			(layers "F.Cu" "F.Mask" "F.Paste")
			(net "GND")
		)
		(pad "18" smd rect
			(at -2.050034 -48.874934 90)
			(size 0.519938 1.4986)
			(layers "F.Cu" "F.Mask" "F.Paste")
			(net "M_F_CPU0_SA_DQ<8>")
		)
		(pad "19" smd rect
			(at -2.050034 -48.02505 90)
			(size 0.519938 1.4986)
			(layers "F.Cu" "F.Mask" "F.Paste")
			(net "GND")
		)
		(pad "20" smd rect
			(at -2.050034 -47.174912 90)
			(size 0.519938 1.4986)
			(layers "F.Cu" "F.Mask" "F.Paste")
			(net "M_F_CPU0_SA_DQ<9>")
		)
		(pad "21" smd rect
			(at -2.050034 -46.325028 90)
			(size 0.519938 1.4986)
			(layers "F.Cu" "F.Mask" "F.Paste")
			(net "GND")
		)
		(pad "22" smd rect
			(at -2.050034 -45.47489 90)
			(size 0.519938 1.4986)
			(layers "F.Cu" "F.Mask" "F.Paste")
			(net "M_F_CPU0_SA_DQS_DP<1>")
		)
		(pad "23" smd rect
			(at -2.050034 -44.625006 90)
			(size 0.519938 1.4986)
			(layers "F.Cu" "F.Mask" "F.Paste")
			(net "M_F_CPU0_SA_DQS_DN<1>")
		)
		(pad "24" smd rect
			(at -2.050034 -43.775122 90)
			(size 0.519938 1.4986)
			(layers "F.Cu" "F.Mask" "F.Paste")
			(net "GND")
		)
		(pad "25" smd rect
			(at -2.050034 -42.924984 90)
			(size 0.519938 1.4986)
			(layers "F.Cu" "F.Mask" "F.Paste")
			(net "M_F_CPU0_SA_DQ<12>")
		)
		(pad "26" smd rect
			(at -2.050034 -42.0751 90)
			(size 0.519938 1.4986)
			(layers "F.Cu" "F.Mask" "F.Paste")
			(net "GND")
		)
		(pad "27" smd rect
			(at -2.050034 -41.224962 90)
			(size 0.519938 1.4986)
			(layers "F.Cu" "F.Mask" "F.Paste")
			(net "M_F_CPU0_SA_DQ<13>")
		)
		(pad "28" smd rect
			(at -2.050034 -40.375078 90)
			(size 0.519938 1.4986)
			(layers "F.Cu" "F.Mask" "F.Paste")
			(net "GND")
		)
		(pad "29" smd rect
			(at -2.050034 -39.52494 90)
			(size 0.519938 1.4986)
			(layers "F.Cu" "F.Mask" "F.Paste")
			(net "M_F_CPU0_SA_DQ<16>")
		)
		(pad "30" smd rect
			(at -2.050034 -38.675056 90)
			(size 0.519938 1.4986)
			(layers "F.Cu" "F.Mask" "F.Paste")
			(net "GND")
		)
		(pad "31" smd rect
			(at -2.050034 -37.824918 90)
			(size 0.519938 1.4986)
			(layers "F.Cu" "F.Mask" "F.Paste")
			(net "M_F_CPU0_SA_DQ<17>")
		)
		(pad "32" smd rect
			(at -2.050034 -36.975034 90)
			(size 0.519938 1.4986)
			(layers "F.Cu" "F.Mask" "F.Paste")
			(net "GND")
		)
		(pad "33" smd rect
			(at -2.050034 -36.124896 90)
			(size 0.519938 1.4986)
			(layers "F.Cu" "F.Mask" "F.Paste")
			(net "M_F_CPU0_SA_DQS_DP<2>")
		)
		(pad "34" smd rect
			(at -2.050034 -35.275012 90)
			(size 0.519938 1.4986)
			(layers "F.Cu" "F.Mask" "F.Paste")
			(net "M_F_CPU0_SA_DQS_DN<2>")
		)
		(pad "35" smd rect
			(at -2.050034 -34.425128 90)
			(size 0.519938 1.4986)
			(layers "F.Cu" "F.Mask" "F.Paste")
			(net "GND")
		)
		(pad "36" smd rect
			(at -2.050034 -33.57499 90)
			(size 0.519938 1.4986)
			(layers "F.Cu" "F.Mask" "F.Paste")
			(net "M_F_CPU0_SA_DQ<20>")
		)
		(pad "37" smd rect
			(at -2.050034 -32.725106 90)
			(size 0.519938 1.4986)
			(layers "F.Cu" "F.Mask" "F.Paste")
			(net "GND")
		)
		(pad "38" smd rect
			(at -2.050034 -31.874968 90)
			(size 0.519938 1.4986)
			(layers "F.Cu" "F.Mask" "F.Paste")
			(net "M_F_CPU0_SA_DQ<21>")
		)
		(pad "39" smd rect
			(at -2.050034 -31.025084 90)
			(size 0.519938 1.4986)
			(layers "F.Cu" "F.Mask" "F.Paste")
			(net "GND")
		)
		(pad "40" smd rect
			(at -2.050034 -30.174946 90)
			(size 0.519938 1.4986)
			(layers "F.Cu" "F.Mask" "F.Paste")
			(net "M_F_CPU0_SA_DQ<24>")
		)
		(pad "41" smd rect
			(at -2.050034 -29.325062 90)
			(size 0.519938 1.4986)
			(layers "F.Cu" "F.Mask" "F.Paste")
			(net "GND")
		)
		(pad "42" smd rect
			(at -2.050034 -28.474924 90)
			(size 0.519938 1.4986)
			(layers "F.Cu" "F.Mask" "F.Paste")
			(net "M_F_CPU0_SA_DQ<25>")
		)
		(pad "43" smd rect
			(at -2.050034 -27.62504 90)
			(size 0.519938 1.4986)
			(layers "F.Cu" "F.Mask" "F.Paste")
			(net "GND")
		)
		(pad "44" smd rect
			(at -2.050034 -26.774902 90)
			(size 0.519938 1.4986)
			(layers "F.Cu" "F.Mask" "F.Paste")
			(net "M_F_CPU0_SA_DQS_DP<3>")
		)
		(pad "45" smd rect
			(at -2.050034 -25.925018 90)
			(size 0.519938 1.4986)
			(layers "F.Cu" "F.Mask" "F.Paste")
			(net "M_F_CPU0_SA_DQS_DN<3>")
		)
		(pad "46" smd rect
			(at -2.050034 -25.07488 90)
			(size 0.519938 1.4986)
			(layers "F.Cu" "F.Mask" "F.Paste")
			(net "GND")
		)
		(pad "47" smd rect
			(at -2.050034 -24.224996 90)
			(size 0.519938 1.4986)
			(layers "F.Cu" "F.Mask" "F.Paste")
			(net "M_F_CPU0_SA_DQ<28>")
		)
		(pad "48" smd rect
			(at -2.050034 -23.375112 90)
			(size 0.519938 1.4986)
			(layers "F.Cu" "F.Mask" "F.Paste")
			(net "GND")
		)
		(pad "49" smd rect
			(at -2.050034 -22.524974 90)
			(size 0.519938 1.4986)
			(layers "F.Cu" "F.Mask" "F.Paste")
			(net "M_F_CPU0_SA_DQ<29>")
		)
		(pad "50" smd rect
			(at -2.050034 -21.67509 90)
			(size 0.519938 1.4986)
			(layers "F.Cu" "F.Mask" "F.Paste")
			(net "GND")
		)
		(pad "51" smd rect
			(at -2.050034 -20.824952 90)
			(size 0.519938 1.4986)
			(layers "F.Cu" "F.Mask" "F.Paste")
			(net "M_F_CPU0_SA_CB<0>")
		)
		(pad "52" smd rect
			(at -2.050034 -19.975068 90)
			(size 0.519938 1.4986)
			(layers "F.Cu" "F.Mask" "F.Paste")
			(net "GND")
		)
		(pad "53" smd rect
			(at -2.050034 -19.12493 90)
			(size 0.519938 1.4986)
			(layers "F.Cu" "F.Mask" "F.Paste")
			(net "M_F_CPU0_SA_CB<1>")
		)
		(pad "54" smd rect
			(at -2.050034 -18.275046 90)
			(size 0.519938 1.4986)
			(layers "F.Cu" "F.Mask" "F.Paste")
			(net "GND")
		)
		(pad "55" smd rect
			(at -2.050034 -17.424908 90)
			(size 0.519938 1.4986)
			(layers "F.Cu" "F.Mask" "F.Paste")
			(net "M_F_CPU0_SA_DQS_DP<4>")
		)
		(pad "56" smd rect
			(at -2.050034 -16.575024 90)
			(size 0.519938 1.4986)
			(layers "F.Cu" "F.Mask" "F.Paste")
			(net "M_F_CPU0_SA_DQS_DN<4>")
		)
		(pad "57" smd rect
			(at -2.050034 -15.724886 90)
			(size 0.519938 1.4986)
			(layers "F.Cu" "F.Mask" "F.Paste")
			(net "GND")
		)
		(pad "58" smd rect
			(at -2.050034 -14.875002 90)
			(size 0.519938 1.4986)
			(layers "F.Cu" "F.Mask" "F.Paste")
			(net "M_F_CPU0_SA_CB<4>")
		)
		(pad "59" smd rect
			(at -2.050034 -14.025118 90)
			(size 0.519938 1.4986)
			(layers "F.Cu" "F.Mask" "F.Paste")
			(net "GND")
		)
		(pad "60" smd rect
			(at -2.050034 -13.17498 90)
			(size 0.519938 1.4986)
			(layers "F.Cu" "F.Mask" "F.Paste")
			(net "M_F_CPU0_SA_CB<5>")
		)
		(pad "61" smd rect
			(at -2.050034 -12.325096 90)
			(size 0.519938 1.4986)
			(layers "F.Cu" "F.Mask" "F.Paste")
			(net "GND")
		)
		(pad "62" smd rect
			(at -2.050034 -11.474958 90)
			(size 0.519938 1.4986)
			(layers "F.Cu" "F.Mask" "F.Paste")
			(net "M_F_CPU0_ALERT_N")
		)
		(pad "63" smd rect
			(at -2.050034 -10.625074 90)
			(size 0.519938 1.4986)
			(layers "F.Cu" "F.Mask" "F.Paste")
			(net "GND")
		)
		(pad "64" smd rect
			(at -2.050034 -9.774936 90)
			(size 0.519938 1.4986)
			(layers "F.Cu" "F.Mask" "F.Paste")
			(net "M_F_CPU0_SA_CS_N<0>")
		)
		(pad "65" smd rect
			(at -2.050034 -8.925052 90)
			(size 0.519938 1.4986)
			(layers "F.Cu" "F.Mask" "F.Paste")
			(net "GND")
		)
		(pad "66" smd rect
			(at -2.050034 -8.074914 90)
			(size 0.519938 1.4986)
			(layers "F.Cu" "F.Mask" "F.Paste")
			(net "M_F_CPU0_SA_CA<0>")
		)
		(pad "67" smd rect
			(at -2.050034 -7.22503 90)
			(size 0.519938 1.4986)
			(layers "F.Cu" "F.Mask" "F.Paste")
			(net "GND")
		)
		(pad "68" smd rect
			(at -2.050034 -6.374892 90)
			(size 0.519938 1.4986)
			(layers "F.Cu" "F.Mask" "F.Paste")
			(net "M_F_CPU0_SA_CA<2>")
		)
		(pad "69" smd rect
			(at -2.050034 -5.525008 90)
			(size 0.519938 1.4986)
			(layers "F.Cu" "F.Mask" "F.Paste")
			(net "GND")
		)
		(pad "70" smd rect
			(at -2.050034 -4.675124 90)
			(size 0.519938 1.4986)
			(layers "F.Cu" "F.Mask" "F.Paste")
			(net "M_F_CPU0_SA_CA<4>")
		)
		(pad "71" smd rect
			(at -2.050034 -3.824986 90)
			(size 0.519938 1.4986)
			(layers "F.Cu" "F.Mask" "F.Paste")
			(net "GND")
		)
		(pad "72" smd rect
			(at -2.050034 -2.975102 90)
			(size 0.519938 1.4986)
			(layers "F.Cu" "F.Mask" "F.Paste")
			(net "M_F_CPU0_SA_CA<6>")
		)
		(pad "73" smd rect
			(at -2.050034 -2.124964 90)
			(size 0.519938 1.4986)
			(layers "F.Cu" "F.Mask" "F.Paste")
			(net "GND")
		)
		(pad "74" smd rect
			(at -2.050034 -1.27508 90)
			(size 0.519938 1.4986)
			(layers "F.Cu" "F.Mask" "F.Paste")
			(net "M_F_CPU0_SA_PAR")
		)
		(pad "75" smd rect
			(at -2.050034 -0.424942 90)
			(size 0.519938 1.4986)
			(layers "F.Cu" "F.Mask" "F.Paste")
			(net "GND")
		)
		(pad "76" smd rect
			(at -2.050034 5.525008 90)
			(size 0.519938 1.4986)
			(layers "F.Cu" "F.Mask" "F.Paste")
			(net "M_F_CPU0_SB_CA<0>")
		)
		(pad "77" smd rect
			(at -2.050034 6.374892 90)
			(size 0.519938 1.4986)
			(layers "F.Cu" "F.Mask" "F.Paste")
			(net "GND")
		)
		(pad "78" smd rect
			(at -2.050034 7.22503 90)
			(size 0.519938 1.4986)
			(layers "F.Cu" "F.Mask" "F.Paste")
			(net "M_F_CPU0_SB_CA<2>")
		)
		(pad "79" smd rect
			(at -2.050034 8.074914 90)
			(size 0.519938 1.4986)
			(layers "F.Cu" "F.Mask" "F.Paste")
			(net "GND")
		)
		(pad "80" smd rect
			(at -2.050034 8.925052 90)
			(size 0.519938 1.4986)
			(layers "F.Cu" "F.Mask" "F.Paste")
			(net "M_F_CPU0_SB_CA<4>")
		)
		(pad "81" smd rect
			(at -2.050034 9.774936 90)
			(size 0.519938 1.4986)
			(layers "F.Cu" "F.Mask" "F.Paste")
			(net "GND")
		)
		(pad "82" smd rect
			(at -2.050034 10.625074 90)
			(size 0.519938 1.4986)
			(layers "F.Cu" "F.Mask" "F.Paste")
			(net "M_F_CPU0_SB_CA<6>")
		)
		(pad "83" smd rect
			(at -2.050034 11.474958 90)
			(size 0.519938 1.4986)
			(layers "F.Cu" "F.Mask" "F.Paste")
			(net "GND")
		)
		(pad "84" smd rect
			(at -2.050034 12.325096 90)
			(size 0.519938 1.4986)
			(layers "F.Cu" "F.Mask" "F.Paste")
			(net "M_F_CPU0_SB_CS_N<0>")
		)
		(pad "85" smd rect
			(at -2.050034 13.17498 90)
			(size 0.519938 1.4986)
			(layers "F.Cu" "F.Mask" "F.Paste")
			(net "GND")
		)
		(pad "86" smd rect
			(at -2.050034 14.025118 90)
			(size 0.519938 1.4986)
			(layers "F.Cu" "F.Mask" "F.Paste")
			(net "M_F_CPU0_SA_RSP<0>")
		)
		(pad "87" smd rect
			(at -2.050034 14.875002 90)
			(size 0.519938 1.4986)
			(layers "F.Cu" "F.Mask" "F.Paste")
			(net "M_F_CPU0_SB_RSP<0>")
		)
		(pad "88" smd rect
			(at -2.050034 15.724886 90)
			(size 0.519938 1.4986)
			(layers "F.Cu" "F.Mask" "F.Paste")
			(net "GND")
		)
		(pad "89" smd rect
			(at -2.050034 16.575024 90)
			(size 0.519938 1.4986)
			(layers "F.Cu" "F.Mask" "F.Paste")
			(net "M_F_CPU0_SB_CB<4>")
		)
		(pad "90" smd rect
			(at -2.050034 17.424908 90)
			(size 0.519938 1.4986)
			(layers "F.Cu" "F.Mask" "F.Paste")
			(net "GND")
		)
		(pad "91" smd rect
			(at -2.050034 18.275046 90)
			(size 0.519938 1.4986)
			(layers "F.Cu" "F.Mask" "F.Paste")
			(net "M_F_CPU0_SB_CB<5>")
		)
		(pad "92" smd rect
			(at -2.050034 19.12493 90)
			(size 0.519938 1.4986)
			(layers "F.Cu" "F.Mask" "F.Paste")
			(net "GND")
		)
		(pad "93" smd rect
			(at -2.050034 19.975068 90)
			(size 0.519938 1.4986)
			(layers "F.Cu" "F.Mask" "F.Paste")
			(net "M_F_CPU0_SB_DQS_DP<9>")
		)
		(pad "94" smd rect
			(at -2.050034 20.824952 90)
			(size 0.519938 1.4986)
			(layers "F.Cu" "F.Mask" "F.Paste")
			(net "M_F_CPU0_SB_DQS_DN<9>")
		)
		(pad "95" smd rect
			(at -2.050034 21.67509 90)
			(size 0.519938 1.4986)
			(layers "F.Cu" "F.Mask" "F.Paste")
			(net "GND")
		)
		(pad "96" smd rect
			(at -2.050034 22.524974 90)
			(size 0.519938 1.4986)
			(layers "F.Cu" "F.Mask" "F.Paste")
			(net "M_F_CPU0_SB_CB<0>")
		)
		(pad "97" smd rect
			(at -2.050034 23.375112 90)
			(size 0.519938 1.4986)
			(layers "F.Cu" "F.Mask" "F.Paste")
			(net "GND")
		)
		(pad "98" smd rect
			(at -2.050034 24.224996 90)
			(size 0.519938 1.4986)
			(layers "F.Cu" "F.Mask" "F.Paste")
			(net "M_F_CPU0_SB_CB<1>")
		)
		(pad "99" smd rect
			(at -2.050034 25.07488 90)
			(size 0.519938 1.4986)
			(layers "F.Cu" "F.Mask" "F.Paste")
			(net "GND")
		)
		(pad "100" smd rect
			(at -2.050034 25.925018 90)
			(size 0.519938 1.4986)
			(layers "F.Cu" "F.Mask" "F.Paste")
			(net "M_F_CPU0_SB_DQ<0>")
		)
		(pad "101" smd rect
			(at -2.050034 26.774902 90)
			(size 0.519938 1.4986)
			(layers "F.Cu" "F.Mask" "F.Paste")
			(net "GND")
		)
		(pad "102" smd rect
			(at -2.050034 27.62504 90)
			(size 0.519938 1.4986)
			(layers "F.Cu" "F.Mask" "F.Paste")
			(net "M_F_CPU0_SB_DQ<1>")
		)
		(pad "103" smd rect
			(at -2.050034 28.474924 90)
			(size 0.519938 1.4986)
			(layers "F.Cu" "F.Mask" "F.Paste")
			(net "GND")
		)
		(pad "104" smd rect
			(at -2.050034 29.325062 90)
			(size 0.519938 1.4986)
			(layers "F.Cu" "F.Mask" "F.Paste")
			(net "M_F_CPU0_SB_DQS_DP<0>")
		)
		(pad "105" smd rect
			(at -2.050034 30.174946 90)
			(size 0.519938 1.4986)
			(layers "F.Cu" "F.Mask" "F.Paste")
			(net "M_F_CPU0_SB_DQS_DN<0>")
		)
		(pad "106" smd rect
			(at -2.050034 31.025084 90)
			(size 0.519938 1.4986)
			(layers "F.Cu" "F.Mask" "F.Paste")
			(net "GND")
		)
		(pad "107" smd rect
			(at -2.050034 31.874968 90)
			(size 0.519938 1.4986)
			(layers "F.Cu" "F.Mask" "F.Paste")
			(net "M_F_CPU0_SB_DQ<4>")
		)
		(pad "108" smd rect
			(at -2.050034 32.725106 90)
			(size 0.519938 1.4986)
			(layers "F.Cu" "F.Mask" "F.Paste")
			(net "GND")
		)
		(pad "109" smd rect
			(at -2.050034 33.57499 90)
			(size 0.519938 1.4986)
			(layers "F.Cu" "F.Mask" "F.Paste")
			(net "M_F_CPU0_SB_DQ<5>")
		)
		(pad "110" smd rect
			(at -2.050034 34.425128 90)
			(size 0.519938 1.4986)
			(layers "F.Cu" "F.Mask" "F.Paste")
			(net "GND")
		)
		(pad "111" smd rect
			(at -2.050034 35.275012 90)
			(size 0.519938 1.4986)
			(layers "F.Cu" "F.Mask" "F.Paste")
			(net "M_F_CPU0_SB_DQ<8>")
		)
		(pad "112" smd rect
			(at -2.050034 36.124896 90)
			(size 0.519938 1.4986)
			(layers "F.Cu" "F.Mask" "F.Paste")
			(net "GND")
		)
		(pad "113" smd rect
			(at -2.050034 36.975034 90)
			(size 0.519938 1.4986)
			(layers "F.Cu" "F.Mask" "F.Paste")
			(net "M_F_CPU0_SB_DQ<9>")
		)
	)
)
